(kicad_pcb
	(version 20241229)
	(generator "pcbnew")
	(generator_version "9.0")
	(general
		(thickness 1.62)
		(legacy_teardrops no)
	)
	(paper "A3")
	(title_block
		(title "COM Express 7 Baseboard")
		(date "2025-02-04")
		(rev "1.1.2")
		(company "Antmicro Ltd")
		(comment 1 "www.antmicro.com")
		(comment 9 "footprint 223 of 802 (J8), pads 44-71 of 71")
	)
	(layers
		(0 "F.Cu" signal)
		(4 "In1.Cu" signal)
		(6 "In2.Cu" signal)
		(8 "In3.Cu" signal)
		(10 "In4.Cu" signal)
		(12 "In5.Cu" signal)
		(14 "In6.Cu" signal)
		(2 "B.Cu" signal)
		(9 "F.Adhes" user "F.Adhesive")
		(11 "B.Adhes" user "B.Adhesive")
		(13 "F.Paste" user)
		(15 "B.Paste" user)
		(5 "F.SilkS" user "F.Silkscreen")
		(7 "B.SilkS" user "B.Silkscreen")
		(1 "F.Mask" user)
		(3 "B.Mask" user)
		(17 "Dwgs.User" user "User.Drawings")
		(19 "Cmts.User" user "User.Comments")
		(21 "Eco1.User" user "User.Eco1")
		(23 "Eco2.User" user "User.Eco2")
		(25 "Edge.Cuts" user)
		(27 "Margin" user)
		(31 "F.CrtYd" user "F.Courtyard")
		(29 "B.CrtYd" user "B.Courtyard")
		(35 "F.Fab" user)
		(33 "B.Fab" user)
	)
	(footprint "antmicro-footprints:Bus_M.2_Socket_Key_M_TE_1-2199230-6"
		(layer "F.Cu")
		(at 295.45 77.81)
		(property "Reference" "J8"
			(at -11.35 -5.076 0)
			(layer "F.SilkS")
			(effects
				(font
					(size 0.7 0.7)
					(thickness 0.15)
				)
				(justify left bottom)
			)
		)
		(property "Value" "Bus_M.2_1-2199230-6"
			(at -11.25 6.124 0)
			(layer "F.Fab")
			(effects
				(font
					(size 0.7 0.7)
					(thickness 0.15)
				)
				(justify left bottom)
			)
		)
		(property "Datasheet" "https://www.te.com/commerce/DocumentDelivery/DDEController?Action=srchrtrv&DocNm=2199230&DocType=Customer+Drawing&DocLang=English"
			(at 0 0 0)
			(layer "F.Fab")
			(hide yes)
			(effects
				(font
					(size 1.27 1.27)
					(thickness 0.15)
				)
			)
		)
		(property "Author" "Antmicro"
			(at 0 0 0)
			(layer "F.Fab")
			(hide yes)
			(effects
				(font
					(size 1 1)
					(thickness 0.15)
				)
			)
		)
		(property "License" "Apache-2.0"
			(at 0 0 0)
			(layer "F.Fab")
			(hide yes)
			(effects
				(font
					(size 1 1)
					(thickness 0.15)
				)
			)
		)
		(property "MPN" "1-2199230-6"
			(at 0 0 0)
			(layer "F.Fab")
			(hide yes)
			(effects
				(font
					(size 1 1)
					(thickness 0.15)
				)
			)
		)
		(property "Manufacturer" "TE Connectivity"
			(at 0 0 0)
			(layer "F.Fab")
			(hide yes)
			(effects
				(font
					(size 1 1)
					(thickness 0.15)
				)
			)
		)
		(sheetname "M.2 key M #2")
		(sheetfile "m2keym.kicad_sch")
		(attr smd)
		(pad "42" smd rect
			(at 0.998 3.773)
			(size 0.3 1.55)
			(layers "F.Cu" "F.Mask" "F.Paste")
			(net 263 "unconnected-(J8-SMB_DATA-Pad42)")
			(pinfunction "SMB_DATA")
			(pintype "bidirectional+no_connect")
			(teardrops
				(best_length_ratio 0.2)
				(max_length 1)
				(best_width_ratio 0.9)
				(max_width 2)
				(curved_edges yes)
				(filter_ratio 0.9)
				(enabled yes)
				(allow_two_segments yes)
				(prefer_zone_connections yes)
			)
		)
		(pad "43" smd rect
			(at 1.249 -3.775)
			(size 0.3 1.55)
			(layers "F.Cu" "F.Mask" "F.Paste")
			(net 86 "/Com Express 7 Interfaces/PCIe_{B2Ax4}.RX0-")
			(pinfunction "PER0_P")
			(pintype "output")
			(teardrops
				(best_length_ratio 0.2)
				(max_length 1)
				(best_width_ratio 0.9)
				(max_width 2)
				(curved_edges yes)
				(filter_ratio 0.9)
				(enabled yes)
				(allow_two_segments yes)
				(prefer_zone_connections yes)
			)
		)
		(pad "44" smd rect
			(at 1.499 3.773)
			(size 0.3 1.55)
			(layers "F.Cu" "F.Mask" "F.Paste")
			(net 265 "unconnected-(J8-ALERT-Pad44)")
			(pinfunction "ALERT")
			(pintype "output+no_connect")
			(teardrops
				(best_length_ratio 0.2)
				(max_length 1)
				(best_width_ratio 0.9)
				(max_width 2)
				(curved_edges yes)
				(filter_ratio 0.9)
				(enabled yes)
				(allow_two_segments yes)
				(prefer_zone_connections yes)
			)
		)
		(pad "45" smd rect
			(at 1.749 -3.775)
			(size 0.3 1.55)
			(layers "F.Cu" "F.Mask" "F.Paste")
			(net 1 "GND")
			(pinfunction "GND")
			(pintype "passive")
			(teardrops
				(best_length_ratio 0.2)
				(max_length 1)
				(best_width_ratio 0.9)
				(max_width 2)
				(curved_edges yes)
				(filter_ratio 0.9)
				(enabled yes)
				(allow_two_segments yes)
				(prefer_zone_connections yes)
			)
		)
		(pad "46" smd rect
			(at 1.999 3.773)
			(size 0.3 1.55)
			(layers "F.Cu" "F.Mask" "F.Paste")
			(net 266 "unconnected-(J8-NC-Pad46)")
			(pinfunction "NC")
			(pintype "no_connect")
			(teardrops
				(best_length_ratio 0.2)
				(max_length 1)
				(best_width_ratio 0.9)
				(max_width 2)
				(curved_edges yes)
				(filter_ratio 0.9)
				(enabled yes)
				(allow_two_segments yes)
				(prefer_zone_connections yes)
			)
		)
		(pad "47" smd rect
			(at 2.249 -3.775)
			(size 0.3 1.55)
			(layers "F.Cu" "F.Mask" "F.Paste")
			(net 324 "/Com Express 7 Interfaces/PCIe_{B2Ax4}.TX0+")
			(pinfunction "PET0_N")
			(pintype "input")
			(teardrops
				(best_length_ratio 0.2)
				(max_length 1)
				(best_width_ratio 0.9)
				(max_width 2)
				(curved_edges yes)
				(filter_ratio 0.9)
				(enabled yes)
				(allow_two_segments yes)
				(prefer_zone_connections yes)
			)
		)
		(pad "48" smd rect
			(at 2.499 3.773)
			(size 0.3 1.55)
			(layers "F.Cu" "F.Mask" "F.Paste")
			(net 268 "unconnected-(J8-NC-Pad48)")
			(pinfunction "NC")
			(pintype "no_connect")
			(teardrops
				(best_length_ratio 0.2)
				(max_length 1)
				(best_width_ratio 0.9)
				(max_width 2)
				(curved_edges yes)
				(filter_ratio 0.9)
				(enabled yes)
				(allow_two_segments yes)
				(prefer_zone_connections yes)
			)
		)
		(pad "49" smd rect
			(at 2.749 -3.775)
			(size 0.3 1.55)
			(layers "F.Cu" "F.Mask" "F.Paste")
			(net 325 "/Com Express 7 Interfaces/PCIe_{B2Ax4}.TX0-")
			(pinfunction "PET0_P")
			(pintype "input")
			(teardrops
				(best_length_ratio 0.2)
				(max_length 1)
				(best_width_ratio 0.9)
				(max_width 2)
				(curved_edges yes)
				(filter_ratio 0.9)
				(enabled yes)
				(allow_two_segments yes)
				(prefer_zone_connections yes)
			)
		)
		(pad "50" smd rect
			(at 2.999 3.773)
			(size 0.3 1.55)
			(layers "F.Cu" "F.Mask" "F.Paste")
			(net 270 "/M.2 key M #2/~{PERST_D}")
			(pinfunction "~{PERST}")
			(pintype "input")
			(teardrops
				(best_length_ratio 0.2)
				(max_length 1)
				(best_width_ratio 0.9)
				(max_width 2)
				(curved_edges yes)
				(filter_ratio 0.9)
				(enabled yes)
				(allow_two_segments yes)
				(prefer_zone_connections yes)
			)
		)
		(pad "51" smd rect
			(at 3.249 -3.775)
			(size 0.3 1.55)
			(layers "F.Cu" "F.Mask" "F.Paste")
			(net 1 "GND")
			(pinfunction "GND")
			(pintype "passive")
			(teardrops
				(best_length_ratio 0.2)
				(max_length 1)
				(best_width_ratio 0.9)
				(max_width 2)
				(curved_edges yes)
				(filter_ratio 0.9)
				(enabled yes)
				(allow_two_segments yes)
				(prefer_zone_connections yes)
			)
		)
		(pad "52" smd rect
			(at 3.499 3.773)
			(size 0.3 1.55)
			(layers "F.Cu" "F.Mask" "F.Paste")
			(net 530 "/M.2 key M #2/~{CLKREQ}")
			(pinfunction "~{CLKREQ}")
			(pintype "output")
			(teardrops
				(best_length_ratio 0.2)
				(max_length 1)
				(best_width_ratio 0.9)
				(max_width 2)
				(curved_edges yes)
				(filter_ratio 0.9)
				(enabled yes)
				(allow_two_segments yes)
				(prefer_zone_connections yes)
			)
		)
		(pad "53" smd rect
			(at 3.749 -3.775)
			(size 0.3 1.55)
			(layers "F.Cu" "F.Mask" "F.Paste")
			(net 271 "/M.2 key M #2/PCIE_{REF}.CK-")
			(pinfunction "REFCLK_N")
			(pintype "input")
			(teardrops
				(best_length_ratio 0.2)
				(max_length 1)
				(best_width_ratio 0.9)
				(max_width 2)
				(curved_edges yes)
				(filter_ratio 0.9)
				(enabled yes)
				(allow_two_segments yes)
				(prefer_zone_connections yes)
			)
		)
		(pad "54" smd rect
			(at 3.999 3.773)
			(size 0.3 1.55)
			(layers "F.Cu" "F.Mask" "F.Paste")
			(net 272 "unconnected-(J8-~{PEWAKE}-Pad54)")
			(pinfunction "~{PEWAKE}")
			(pintype "input+no_connect")
			(teardrops
				(best_length_ratio 0.2)
				(max_length 1)
				(best_width_ratio 0.9)
				(max_width 2)
				(curved_edges yes)
				(filter_ratio 0.9)
				(enabled yes)
				(allow_two_segments yes)
				(prefer_zone_connections yes)
			)
		)
		(pad "55" smd rect
			(at 4.248 -3.775)
			(size 0.3 1.55)
			(layers "F.Cu" "F.Mask" "F.Paste")
			(net 273 "/M.2 key M #2/PCIE_{REF}.CK+")
			(pinfunction "REFCLK_P")
			(pintype "input")
			(teardrops
				(best_length_ratio 0.2)
				(max_length 1)
				(best_width_ratio 0.9)
				(max_width 2)
				(curved_edges yes)
				(filter_ratio 0.9)
				(enabled yes)
				(allow_two_segments yes)
				(prefer_zone_connections yes)
			)
		)
		(pad "56" smd rect
			(at 4.498 3.773)
			(size 0.3 1.55)
			(layers "F.Cu" "F.Mask" "F.Paste")
			(net 274 "unconnected-(J8-NC-Pad56)")
			(pinfunction "NC")
			(pintype "no_connect")
			(teardrops
				(best_length_ratio 0.2)
				(max_length 1)
				(best_width_ratio 0.9)
				(max_width 2)
				(curved_edges yes)
				(filter_ratio 0.9)
				(enabled yes)
				(allow_two_segments yes)
				(prefer_zone_connections yes)
			)
		)
		(pad "57" smd rect
			(at 4.748 -3.775)
			(size 0.3 1.55)
			(layers "F.Cu" "F.Mask" "F.Paste")
			(net 1 "GND")
			(pinfunction "GND")
			(pintype "passive")
			(teardrops
				(best_length_ratio 0.2)
				(max_length 1)
				(best_width_ratio 0.9)
				(max_width 2)
				(curved_edges yes)
				(filter_ratio 0.9)
				(enabled yes)
				(allow_two_segments yes)
				(prefer_zone_connections yes)
			)
		)
		(pad "58" smd rect
			(at 4.998 3.773)
			(size 0.3 1.55)
			(layers "F.Cu" "F.Mask" "F.Paste")
			(net 275 "unconnected-(J8-NC-Pad58)")
			(pinfunction "NC")
			(pintype "no_connect")
			(teardrops
				(best_length_ratio 0.2)
				(max_length 1)
				(best_width_ratio 0.9)
				(max_width 2)
				(curved_edges yes)
				(filter_ratio 0.9)
				(enabled yes)
				(allow_two_segments yes)
				(prefer_zone_connections yes)
			)
		)
		(pad "67" smd rect
			(at 7.248 -3.775)
			(size 0.3 1.55)
			(layers "F.Cu" "F.Mask" "F.Paste")
			(net 276 "unconnected-(J8-NC-Pad67)")
			(pinfunction "NC")
			(pintype "no_connect")
			(teardrops
				(best_length_ratio 0.2)
				(max_length 1)
				(best_width_ratio 0.9)
				(max_width 2)
				(curved_edges yes)
				(filter_ratio 0.9)
				(enabled yes)
				(allow_two_segments yes)
				(prefer_zone_connections yes)
			)
		)
		(pad "68" smd rect
			(at 7.498 3.773)
			(size 0.3 1.55)
			(layers "F.Cu" "F.Mask" "F.Paste")
			(net 277 "Net-(J8-SUSCLK)")
			(pinfunction "SUSCLK")
			(pintype "input")
			(teardrops
				(best_length_ratio 0.2)
				(max_length 1)
				(best_width_ratio 0.9)
				(max_width 2)
				(curved_edges yes)
				(filter_ratio 0.9)
				(enabled yes)
				(allow_two_segments yes)
				(prefer_zone_connections yes)
			)
		)
		(pad "69" smd rect
			(at 7.748 -3.775)
			(size 0.3 1.55)
			(layers "F.Cu" "F.Mask" "F.Paste")
			(net 278 "unconnected-(J8-NC-Pad69)")
			(pinfunction "NC")
			(pintype "no_connect")
			(teardrops
				(best_length_ratio 0.2)
				(max_length 1)
				(best_width_ratio 0.9)
				(max_width 2)
				(curved_edges yes)
				(filter_ratio 0.9)
				(enabled yes)
				(allow_two_segments yes)
				(prefer_zone_connections yes)
			)
		)
		(pad "70" smd rect
			(at 7.998 3.773)
			(size 0.3 1.55)
			(layers "F.Cu" "F.Mask" "F.Paste")
			(net 970 "/M.2 key M #2/M2_3V3")
			(pinfunction "3V3")
			(pintype "passive")
			(teardrops
				(best_length_ratio 0.2)
				(max_length 1)
				(best_width_ratio 0.9)
				(max_width 2)
				(curved_edges yes)
				(filter_ratio 0.9)
				(enabled yes)
				(allow_two_segments yes)
				(prefer_zone_connections yes)
			)
		)
		(pad "71" smd rect
			(at 8.247 -3.775)
			(size 0.3 1.55)
			(layers "F.Cu" "F.Mask" "F.Paste")
			(net 1 "GND")
			(pinfunction "GND")
			(pintype "passive")
			(teardrops
				(best_length_ratio 0.2)
				(max_length 1)
				(best_width_ratio 0.9)
				(max_width 2)
				(curved_edges yes)
				(filter_ratio 0.9)
				(enabled yes)
				(allow_two_segments yes)
				(prefer_zone_connections yes)
			)
		)
		(pad "72" smd rect
			(at 8.497 3.773)
			(size 0.3 1.55)
			(layers "F.Cu" "F.Mask" "F.Paste")
			(net 970 "/M.2 key M #2/M2_3V3")
			(pinfunction "3V3")
			(pintype "passive")
			(teardrops
				(best_length_ratio 0.2)
				(max_length 1)
				(best_width_ratio 0.9)
				(max_width 2)
				(curved_edges yes)
				(filter_ratio 0.9)
				(enabled yes)
				(allow_two_segments yes)
				(prefer_zone_connections yes)
			)
		)
		(pad "73" smd rect
			(at 8.747 -3.775)
			(size 0.3 1.55)
			(layers "F.Cu" "F.Mask" "F.Paste")
			(net 1 "GND")
			(pinfunction "GND")
			(pintype "passive")
			(teardrops
				(best_length_ratio 0.2)
				(max_length 1)
				(best_width_ratio 0.9)
				(max_width 2)
				(curved_edges yes)
				(filter_ratio 0.9)
				(enabled yes)
				(allow_two_segments yes)
				(prefer_zone_connections yes)
			)
		)
		(pad "74" smd rect
			(at 8.997 3.773)
			(size 0.3 1.55)
			(layers "F.Cu" "F.Mask" "F.Paste")
			(net 970 "/M.2 key M #2/M2_3V3")
			(pinfunction "3V3")
			(pintype "passive")
			(teardrops
				(best_length_ratio 0.2)
				(max_length 1)
				(best_width_ratio 0.9)
				(max_width 2)
				(curved_edges yes)
				(filter_ratio 0.9)
				(enabled yes)
				(allow_two_segments yes)
				(prefer_zone_connections yes)
			)
		)
		(pad "75" smd rect
			(at 9.247 -3.775)
			(size 0.3 1.55)
			(layers "F.Cu" "F.Mask" "F.Paste")
			(net 1 "GND")
			(pinfunction "GND")
			(pintype "passive")
			(teardrops
				(best_length_ratio 0.2)
				(max_length 1)
				(best_width_ratio 0.9)
				(max_width 2)
				(curved_edges yes)
				(filter_ratio 0.9)
				(enabled yes)
				(allow_two_segments yes)
				(prefer_zone_connections yes)
			)
		)
		(pad "MP1" smd rect
			(at -10.352 -3)
			(size 1.2 2.75)
			(layers "F.Cu" "F.Mask" "F.Paste")
			(net 1 "GND")
			(pinfunction "MP")
			(pintype "passive")
			(teardrops
				(best_length_ratio 0.2)
				(max_length 1)
				(best_width_ratio 0.9)
				(max_width 2)
				(curved_edges yes)
				(filter_ratio 0.9)
				(enabled yes)
				(allow_two_segments yes)
				(prefer_zone_connections yes)
			)
		)
		(pad "MP2" smd rect
			(at 10.349 -3)
			(size 1.2 2.75)
			(layers "F.Cu" "F.Mask" "F.Paste")
			(net 1 "GND")
			(pinfunction "MP")
			(pintype "passive")
			(teardrops
				(best_length_ratio 0.2)
				(max_length 1)
				(best_width_ratio 0.9)
				(max_width 2)
				(curved_edges yes)
				(filter_ratio 0.9)
				(enabled yes)
				(allow_two_segments yes)
				(prefer_zone_connections yes)
			)
		)
	)
)
